FILE_TYPE = CONNECTIVITY;
{Allegro Design Entry HDL 17.2-2016 S081 (4005846) 1/11/2022}
"PAGE_NUMBER" = 29;
0"NC";
1"GND\g";
2"PVDD18_S5_P0\g";
3"ESPI_CPU0_ALERT_N";
4"CPU0_ESPI0_ALERT_N";
5"ESPI_CPU0_R_D3";
6"ESPI_CPU0_R_ALERT_N";
7"CLK_ESPI_CPU0_R_CLK1";
8"PD_ESPI_CPU0_CLK2";
9"ESPI_CPU0_R_CS1_N";
10"RST_CPU0_KBRST_R_N";
11"ESPI_CPU0_R_D2";
12"ESPI_CPU0_D1";
13"SPI_CPU0_D1";
14"CLK_ESPI_CPU0_CLK1";
15"RST_ESPI_CPU0_R_RSTOUT_N";
16"SPI_CPU0_R_TPM_CS_N";
17"ESPI_CPU0_D2";
18"SPI_CPU0_D3";
19"SPI_CPU0_D2";
20"SPI_CPU0_D0";
21"RST_ESPI_CPU0_RSTOUT_N";
22"USB3_CPU0_P10_TX_DN";
23"SCM_USB_OC_BUF_N";
24"USB_OC_N";
25"ESPI_CPU0_CS1_N";
26"ESPI_CPU0_R_D0";
27"SPI_CPU0_R_D2";
28"SPI_CPU0_R_D1";
29"CPU0_ESPI_CS0_N";
30"SPI_CPU0_R_CLK";
31"NC_CPU0_SPI_CS2_N";
32"SPI_CPU0_R_CS1_N";
33"SPI_CPU0_R_CS0_N";
34"PVDD18_S5_P0\g";
35"P1V8_STBY\g";
36"GND\g";
37"PVDD18_S5_P0\g";
38"SPI_CPU0_CS0_N";
39"SPI_CPU0_CS1_N";
40"SPI_CPU0_R_D0";
41"SPI_CPU0_R_D3";
42"ESPI_CPU0_R_D1";
43"SPI_CPU0_CLK";
44"ESPI_CPU0_D3";
45"ESPI_CPU0_D0";
46"SPI_CPU0_TPM_CS_N";
47"ESPI_CPU0_D1";
48"USB3_CPU0_P10_TX_C_DP";
49"USB3_CPU0_P10_RX_DN";
50"USB3_CPU0_P10_TX_C_DN";
51"USB2_CPU0_P0_DN";
52"USB2_CPU0_P0_DP";
53"USB3_CPU0_P10_TX_DP";
54"USB3_CPU0_P10_RX_C_DP";
55"USB3_CPU0_P10_RX_C_DN";
56"SCM_USB_OC_BUF_N";
57"SCM_USB_OC_BU_R_N";
58"SCM_USB_OC_N";
59"ESPI_CPU0_ALERT_N";
60"RST_ESPI_CPU0_RSTOUT_N";
61"ESPI_CPU0_D2";
62"USB3_CPU0_P10_RX_DP";
63"ESPI_CPU0_D3";
64"ESPI_CPU0_D0";
65"ESPI_CPU0_CS1_N";
66"USB2_CPU0_P1_DP";
67"USB2_CPU0_P1_DN";
68"USB2_CPU0_P10_DP";
69"USB2_CPU0_P10_DN";
%"UNIVERSAL_POWER"
"1","(-7925,3675)","0","pure_quanta_power","I277";
;
HDL_POWER"PVDD18_S5_P0"
CDS_LIB"pure_quanta_power";
"A"37;
%"Q_RES"
"2","(-7925,3225)","0","pure_quanta","I282";
;
LOCATION"R457"
$SEC"1"
CDS_SEC"1"
TOLERANCE"5%"
PACK_TYPE"0402LF"
VALUE"4.7K"
MATERIAL"CHIP"
WATTAGE"1/16W"
PART_NUMBER"TMP_QCS24702JB38"
CDS_LIB"pure_quanta";
"A"
$PN"1"37;
"B"
$PN"2"60;
%"Q_RES"
"2","(-8150,3250)","0","pure_quanta","I284";
;
LOCATION"R455"
$SEC"1"
CDS_SEC"1"
PACK_TYPE"0402LF"
VALUE"4.7K"
TOLERANCE"5%"
WATTAGE"1/16W"
MATERIAL"CHIP"
PART_NUMBER"TMP_QCS24702JB38"
CDS_LIB"pure_quanta";
"A"
$PN"1"37;
"B"
$PN"2"65;
%"GENOA_SP5"
"22","(-4675,4825)","0","pure_quanta","I287";
;
LOCATION"U25"
$SEC"22"
CDS_SEC"22"
PART_NUMBER"DGA^6000030"
VALUE"SOCKET6096_13568-001"
MATERIAL"IO"
PART_TYPE"SMLF"
CDS_LIB"pure_quanta"
CDS_LMAN_SYM_OUTLINE"-1100,1225,1100,-1225"
NEEDS_NO_SIZE"TRUE";
"ESPI_RSTOUT_L||AGPIO23"
$PN"DE27"15;
"ESPI_CLK1||SPI_CLK1||AGPIO75"
$PN"DG23"7;
"ESPI_CLK2||AGPIO74"
$PN"DF27"8;
"ESPI0_ALERT_L||AGPIO108"
$PN"DJ22"4;
"AGPIO76||SPI_TPM_CS_L"
$PN"DJ25"16;
"ESPI_CLK0||SPI_CLK0||AGPIO117"
$PN"DJ27"30;
"ESPI1_ALERT_L||AGPIO110"
$PN"DF24"6;
"ESPI_RSTIN_L||KBRST_L||AGPIO129"
$PN"DJ26"10;
"USB01_OC_L||AGPIO265"
$PN"E24"0;
"SPI_CS1_L||AGPIO119"
$PN"DG26"32;
"SPI_CS2_L||AGPIO126"
$PN"DH27"31;
"ESPI0_DAT0||SPI0_DAT0||AGPIO120"
$PN"DF28"40;
"ESPI0_DAT1||SPI0_DAT1||AGPIO121"
$PN"DG22"28;
"ESPI0_DAT2||SPI0_DAT2||AGPIO122"
$PN"DJ28"27;
"ESPI0_DAT3||SPI0_DAT3||AGPIO123"
$PN"DG29"41;
"ESPI1_DAT2||SPI1_DAT2||AGPIO133"
$PN"DF25"11;
"ESPI1_DAT3||SPI1_DAT3||AGPIO134"
$PN"DG25"5;
"ESPI_CS1_L||AGPIO125"
$PN"DJ23"9;
"ESPI1_DAT0||SPI1_DAT0||AGPIO131"
$PN"DH24"26;
"ESPI1_DAT1||SPI1_DAT1||AGPIO132"
$PN"DE24"42;
"SPI_CS0_L||AGPIO118"
$PN"DF30"33;
"USB00_OC_L||AGPIO264"
$PN"E23"23;
"ESPI_CS0_L||AGPIO124"
$PN"DG28"29;
"USB11_OC_L||AGPIO17"
$PN"DH40"0;
"USB10_OC_L||AGPIO16"
$PN"DG40"24;
"USB11_TXP"
$PN"DG58"0;
"USB11_TXN"
$PN"DH58"0;
"USB11_RXP"
$PN"DJ62"0;
"USB11_RXN"
$PN"DH62"0;
"USB11_DP"
$PN"DH60"0;
"USB11_DN"
$PN"DJ60"0;
"USB10_TXP"
$PN"DH69"53;
"USB10_TXN"
$PN"DJ69"22;
"USB10_RXP"
$PN"DJ65"54;
"USB10_RXN"
$PN"DH65"55;
"USB10_DP"
$PN"DJ67"68;
"USB10_DN"
$PN"DH67"69;
"USB01_TXP"
$PN"E30"0;
"USB01_TXN"
$PN"E29"0;
"USB01_RXP"
$PN"C29"0;
"USB01_RXN"
$PN"C28"0;
"USB01_DP"
$PN"A28"66;
"USB01_DN"
$PN"A29"67;
"USB00_TXP"
$PN"C25"0;
"USB00_TXN"
$PN"C26"0;
"USB00_RXP"
$PN"E27"0;
"USB00_RXN"
$PN"E26"0;
"USB00_DP"
$PN"A26"52;
"USB00_DN"
$PN"A25"51;
%"Q_RES"
"1","(-6950,4850)","0","pure_quanta","I327";
;
LOCATION"R470"
$SEC"1"
CDS_SEC"1"
VALUE"33"
PACK_TYPE"0402LF"
PART_NUMBER"CS03302JB29"
TOLERANCE"5%"
MATERIAL"CHIP"
WATTAGE"1/16W"
CDS_LIB"pure_quanta";
"B"
$PN"2"11;
"A"
$PN"1"17;
%"Q_RES"
"1","(-6950,4900)","0","pure_quanta","I328";
;
LOCATION"R469"
$SEC"1"
CDS_SEC"1"
VALUE"33"
PACK_TYPE"0402LF"
PART_NUMBER"CS03302JB29"
TOLERANCE"5%"
MATERIAL"CHIP"
WATTAGE"1/16W"
CDS_LIB"pure_quanta";
"B"
$PN"2"42;
"A"
$PN"1"12;
%"Q_RES"
"1","(-6950,4950)","0","pure_quanta","I329";
;
LOCATION"R468"
$SEC"1"
CDS_SEC"1"
VALUE"33"
PACK_TYPE"0402LF"
PART_NUMBER"CS03302JB29"
TOLERANCE"5%"
MATERIAL"CHIP"
WATTAGE"1/16W"
CDS_LIB"pure_quanta";
"B"
$PN"2"26;
"A"
$PN"1"45;
%"Q_RES"
"1","(-6950,4800)","0","pure_quanta","I330";
;
LOCATION"R471"
$SEC"1"
CDS_SEC"1"
VALUE"33"
PACK_TYPE"0402LF"
PART_NUMBER"CS03302JB29"
TOLERANCE"5%"
MATERIAL"CHIP"
WATTAGE"1/16W"
CDS_LIB"pure_quanta";
"B"
$PN"2"5;
"A"
$PN"1"44;
%"Q_RES"
"1","(-6950,4650)","0","pure_quanta","I331";
;
LOCATION"R472"
$SEC"1"
CDS_SEC"1"
VALUE"33"
PACK_TYPE"0402LF"
PART_NUMBER"CS03302JB29"
TOLERANCE"5%"
MATERIAL"CHIP"
WATTAGE"1/16W"
CDS_LIB"pure_quanta";
"B"
$PN"2"6;
"A"
$PN"1"3;
%"Q_RES"
"1","(-6950,4350)","0","pure_quanta","I332";
;
LOCATION"R474"
$SEC"1"
CDS_SEC"1"
VALUE"0"
PACK_TYPE"0402LF"
PART_NUMBER"CS00002JB38"
TOLERANCE"5%"
MATERIAL"CHIP"
WATTAGE"1/16W"
CDS_LIB"pure_quanta";
"B"
$PN"2"15;
"A"
$PN"1"21;
%"SN74LVC1G07DBVR"
"1","(-2625,2550)","0","pure_quanta","I373";
;
LOCATION"U3"
$SEC"1"
CDS_SEC"1"
PACK_TYPE"SMLF"
VALUE"SN74LVC1G07DBVR"
MATERIAL"IC"
PART_NUMBER"AL1G0007024"
CDS_LIB"pure_quanta"
NEEDS_NO_SIZE"TRUE";
"NC"
$PN"1"0;
"Y"
$PN"4"57;
"GND"
$PN"3"36;
"A"
$PN"2"58;
"VCC"
$PN"5"35;
%"Q_RES"
"1","(-1775,2550)","0","pure_quanta","I377";
;
LOCATION"R589"
$SEC"1"
CDS_SEC"1"
VALUE"0"
PACK_TYPE"0402LF"
PART_NUMBER"CS00002JB38"
TOLERANCE"5%"
MATERIAL"CHIP"
WATTAGE"1/16W"
CDS_LIB"pure_quanta";
"B"
$PN"2"56;
"A"
$PN"1"57;
%"Q_CAP"
"1","(-2975,2850)","2","pure_quanta","I379";
;
LOCATION"C30"
$SEC"1"
CDS_SEC"1"
PACK_TYPE"0402"
VOLTAGE"25V"
PART_NUMBER"CH4104K1B00"
VALUE"0.1UF"
TOLERANCE"10%"
MATERIAL"X7R"
CDS_LIB"pure_quanta";
"B"
$PN"2"1;
"A"
$PN"1"35;
%"UNIVERSAL_GND"
"1","(-2975,2650)","2","pure_quanta_power","I380";
;
HDL_POWER"GND"
CDS_LIB"pure_quanta_power";
"A"1;
%"UNIVERSAL_POWER"
"1","(-1600,3225)","0","pure_quanta_power","I382";
;
HDL_POWER"PVDD18_S5_P0"
CDS_LIB"pure_quanta_power";
"A"2;
%"Q_RES"
"2","(-1600,2950)","0","pure_quanta","I383";
;
LOCATION"R454"
$SEC"1"
CDS_SEC"1"
PACK_TYPE"0402LF"
VALUE"10K"
TOLERANCE"5%"
MATERIAL"CHIP"
WATTAGE"1/16W"
PART_NUMBER"TMP_QCS31002JB28"
BOM_COST"I/O CONNECTOR"
CDS_LIB"pure_quanta";
"A"
$PN"1"2;
"B"
$PN"2"56;
%"UNIVERSAL_GND"
"1","(-2875,2325)","0","pure_quanta_power","I385";
;
HDL_POWER"GND"
CDS_LIB"pure_quanta_power";
"A"36;
%"VCC_CORE"
"1","(-2900,3125)","0","pure_quanta_power","I386";
;
HDL_POWER"P1V8_STBY"
CDS_LIB"pure_quanta_power";
"A"35;
%"Q_CAP_DIFFBUS"
"2","(-2450,4250)","0","pure_quanta","I387";
;
LOCATION"C11"
$SEC"1"
CDS_SEC"1"
VALUE"DIFF BUS_0.22UF"
PACK_TYPE"C0402"
VOLTAGE"16V"
PART_NUMBER"SP_CH4223K1B00"
TOLERANCE"10%"
MATERIAL"X7R"
PIN_NAMES_ROTATE"True"
CDS_LMAN_SYM_OUTLINE"-25,50,25,-50"
CDS_LIB"pure_quanta";
"2"
$PN"2"50;
"1"
$PN"1"22;
%"Q_CAP_DIFFBUS"
"2","(-2450,4300)","0","pure_quanta","I388";
;
LOCATION"C10"
$SEC"1"
CDS_SEC"1"
VALUE"DIFF BUS_0.22UF"
PACK_TYPE"C0402"
VOLTAGE"16V"
PART_NUMBER"SP_CH4223K1B00"
TOLERANCE"10%"
MATERIAL"X7R"
PIN_NAMES_ROTATE"True"
CDS_LMAN_SYM_OUTLINE"-25,50,25,-50"
CDS_LIB"pure_quanta";
"2"
$PN"2"48;
"1"
$PN"1"53;
%"Q_CAP_DIFFBUS"
"2","(-2425,4900)","0","pure_quanta","I391";
;
LOCATION"C29"
$SEC"1"
CDS_SEC"1"
VALUE"DIFF BUS_0.33UF"
PACK_TYPE"C0402"
VOLTAGE"6.3V"
PART_NUMBER"SP_CH4331KEB01"
TOLERANCE"10%"
MATERIAL"X6S"
CDS_LIB"pure_quanta"
CDS_LMAN_SYM_OUTLINE"-25,50,25,-50"
PIN_NAMES_ROTATE"TRUE";
"2"
$PN"2"49;
"1"
$PN"1"55;
%"Q_CAP_DIFFBUS"
"2","(-2425,4950)","0","pure_quanta","I392";
;
LOCATION"C28"
$SEC"1"
CDS_SEC"1"
VALUE"DIFF BUS_0.33UF"
PART_NUMBER"SP_CH4331KEB01"
PACK_TYPE"C0402"
VOLTAGE"6.3V"
TOLERANCE"10%"
MATERIAL"X6S"
CDS_LIB"pure_quanta"
CDS_LMAN_SYM_OUTLINE"-25,50,25,-50"
PIN_NAMES_ROTATE"TRUE";
"2"
$PN"2"62;
"1"
$PN"1"54;
%"Q_RES"
"1","(-6950,5550)","0","pure_quanta","I393";
;
LOCATION"R462"
$SEC"1"
CDS_SEC"1"
VALUE"33"
CDS_LIB"pure_quanta"
PACK_TYPE"0402LF"
PART_NUMBER"CS03302JB29"
TOLERANCE"5%"
MATERIAL"CHIP"
WATTAGE"1/16W";
"B"
$PN"2"9;
"A"
$PN"1"25;
%"UNIVERSAL_POWER"
"1","(-8125,2625)","0","pure_quanta_power","I395";
;
HDL_POWER"PVDD18_S5_P0"
CDS_LIB"pure_quanta_power";
"A"34;
%"Q_RES"
"1","(-7750,2375)","0","pure_quanta","I396";
;
LOCATION"R1503"
$SEC"1"
CDS_SEC"1"
VALUE"30K"
PACK_TYPE"0402LF"
PART_NUMBER"CS33002FB13"
TOLERANCE"1%"
MATERIAL"CHIP"
WATTAGE"1/16W"
CDS_LIB"pure_quanta";
"B"
$PN"2"64;
"A"
$PN"1"34;
%"Q_RES"
"1","(-7750,2325)","0","pure_quanta","I397";
;
LOCATION"R1504"
$SEC"1"
CDS_SEC"1"
VALUE"30K"
PACK_TYPE"0402LF"
PART_NUMBER"CS33002FB13"
TOLERANCE"1%"
MATERIAL"CHIP"
WATTAGE"1/16W"
CDS_LIB"pure_quanta";
"B"
$PN"2"47;
"A"
$PN"1"34;
%"Q_RES"
"1","(-7750,2275)","0","pure_quanta","I398";
;
LOCATION"R1505"
$SEC"1"
CDS_SEC"1"
VALUE"30K"
PACK_TYPE"0402LF"
PART_NUMBER"CS33002FB13"
TOLERANCE"1%"
MATERIAL"CHIP"
WATTAGE"1/16W"
CDS_LIB"pure_quanta";
"B"
$PN"2"61;
"A"
$PN"1"34;
%"Q_RES"
"1","(-7750,2225)","0","pure_quanta","I399";
;
LOCATION"R1506"
$SEC"1"
CDS_SEC"1"
VALUE"30K"
PACK_TYPE"0402LF"
PART_NUMBER"CS33002FB13"
TOLERANCE"1%"
MATERIAL"CHIP"
WATTAGE"1/16W"
CDS_LIB"pure_quanta";
"B"
$PN"2"63;
"A"
$PN"1"34;
%"Q_RES"
"1","(-7750,2150)","0","pure_quanta","I405";
;
LOCATION"R458"
$SEC"1"
CDS_SEC"1"
VALUE"30K"
PACK_TYPE"0402LF"
PART_NUMBER"CS33002FB13"
TOLERANCE"1%"
MATERIAL"CHIP"
WATTAGE"1/16W"
CDS_LIB"pure_quanta";
"B"
$PN"2"59;
"A"
$PN"1"34;
%"Q_RES"
"1","(-6950,4450)","0","pure_quanta","I406";
;
LOCATION"R473"
$SEC"1"
CDS_SEC"1"
VALUE"33"
PACK_TYPE"0402LF"
PART_NUMBER"CS03302JB29"
TOLERANCE"5%"
MATERIAL"CHIP"
WATTAGE"1/16W"
CDS_LIB"pure_quanta";
"B"
$PN"2"7;
"A"
$PN"1"14;
%"Q_RES"
"1","(-6950,5900)","0","pure_quanta","I407";
;
LOCATION"R459"
$SEC"1"
CDS_SEC"1"
VALUE"33"
PACK_TYPE"0402LF"
PART_NUMBER"CS03302JB29"
TOLERANCE"5%"
MATERIAL"CHIP"
WATTAGE"1/16W"
CDS_LIB"pure_quanta";
"B"
$PN"2"33;
"A"
$PN"1"38;
%"Q_RES"
"1","(-6950,5850)","0","pure_quanta","I408";
;
LOCATION"R460"
$SEC"1"
CDS_SEC"1"
VALUE"33"
WATTAGE"1/16W"
MATERIAL"CHIP"
TOLERANCE"5%"
PART_NUMBER"CS03302JB29"
PACK_TYPE"0402LF"
CDS_LIB"pure_quanta";
"B"
$PN"2"32;
"A"
$PN"1"39;
%"Q_RES"
"1","(-6950,5650)","0","pure_quanta","I409";
;
LOCATION"R461"
$SEC"1"
CDS_SEC"1"
VALUE"33"
PACK_TYPE"0402LF"
PART_NUMBER"CS03302JB29"
TOLERANCE"5%"
MATERIAL"CHIP"
WATTAGE"1/16W"
CDS_LIB"pure_quanta";
"B"
$PN"2"30;
"A"
$PN"1"43;
%"Q_RES"
"1","(-6950,5250)","0","pure_quanta","I410";
;
LOCATION"R464"
$SEC"1"
CDS_SEC"1"
VALUE"33"
PACK_TYPE"0402LF"
PART_NUMBER"CS03302JB29"
TOLERANCE"5%"
MATERIAL"CHIP"
WATTAGE"1/16W"
CDS_LIB"pure_quanta";
"B"
$PN"2"40;
"A"
$PN"1"20;
%"Q_RES"
"1","(-6950,5200)","0","pure_quanta","I411";
;
LOCATION"R465"
$SEC"1"
CDS_SEC"1"
VALUE"33"
PACK_TYPE"0402LF"
PART_NUMBER"CS03302JB29"
TOLERANCE"5%"
MATERIAL"CHIP"
WATTAGE"1/16W"
CDS_LIB"pure_quanta";
"B"
$PN"2"28;
"A"
$PN"1"13;
%"Q_RES"
"1","(-6950,5150)","0","pure_quanta","I412";
;
LOCATION"R466"
$SEC"1"
CDS_SEC"1"
VALUE"33"
PACK_TYPE"0402LF"
PART_NUMBER"CS03302JB29"
TOLERANCE"5%"
MATERIAL"CHIP"
WATTAGE"1/16W"
CDS_LIB"pure_quanta";
"B"
$PN"2"27;
"A"
$PN"1"19;
%"Q_RES"
"1","(-6950,5100)","0","pure_quanta","I413";
;
LOCATION"R467"
$SEC"1"
CDS_SEC"1"
VALUE"33"
PACK_TYPE"0402LF"
PART_NUMBER"CS03302JB29"
TOLERANCE"5%"
MATERIAL"CHIP"
WATTAGE"1/16W"
CDS_LIB"pure_quanta";
"B"
$PN"2"41;
"A"
$PN"1"18;
%"Q_RES"
"1","(-6950,4250)","0","pure_quanta","I414";
;
LOCATION"R475"
$SEC"1"
CDS_SEC"1"
VALUE"33"
PACK_TYPE"0402LF"
PART_NUMBER"CS03302JB29"
TOLERANCE"5%"
MATERIAL"CHIP"
WATTAGE"1/16W"
CDS_LIB"pure_quanta";
"B"
$PN"2"16;
"A"
$PN"1"46;
%"Q_RES"
"1","(-6950,5600)","0","pure_quanta","I415";
;
$LOCATION"R1592"
CDS_LOCATION"R1592"
$SEC"1"
CDS_SEC"1"
VALUE"33"
MATERIAL"EMPTY"
CDS_LIB"pure_quanta"
PACK_TYPE"0402LF"
PART_NUMBER"CS03302JB29"
TOLERANCE"5%"
WATTAGE"1/16W";
"B"
$PN"2"29;
"A"
$PN"1"25;
%"Q_RES"
"1","(-6950,4500)","0","pure_quanta","I416";
;
$LOCATION"R1593"
CDS_LOCATION"R1593"
$SEC"1"
CDS_SEC"1"
VALUE"33"
MATERIAL"EMPTY"
PACK_TYPE"0402LF"
PART_NUMBER"CS03302JB29"
TOLERANCE"5%"
WATTAGE"1/16W"
CDS_LIB"pure_quanta";
"B"
$PN"2"4;
"A"
$PN"1"3;
END.
